(kicad_pcb
	(version 20260206)
	(generator "pcbnew")
	(generator_version "10.0")
	(general
		(thickness 1.6)
		(legacy_teardrops no)
	)
	(paper "A4")
	(title_block
		(title "03242023_DA0F0TMBIJ0_F0T_Motherboard_J_brd_V01_OCP.brd")
		(comment 1 "Grand Teton / footprint 3819 of 6105 (J18), pads 1-112 of 291")
	)
	(layers
		(0 "F.Cu" signal "TOP")
		(4 "In1.Cu" signal "GND")
		(6 "In2.Cu" signal "IN1")
		(8 "In3.Cu" signal "GND1")
		(10 "In4.Cu" signal "IN2")
		(12 "In5.Cu" signal "GND2")
		(14 "In6.Cu" signal "IN3")
		(16 "In7.Cu" signal "GND3")
		(18 "In8.Cu" signal "VCC")
		(20 "In9.Cu" signal "VCC1")
		(22 "In10.Cu" signal "GND4")
		(24 "In11.Cu" signal "IN4")
		(26 "In12.Cu" signal "GND5")
		(28 "In13.Cu" signal "IN5")
		(30 "In14.Cu" signal "GND6")
		(32 "In15.Cu" signal "IN6")
		(34 "In16.Cu" signal "GND7")
		(2 "B.Cu" signal "BOTTOM")
		(9 "F.Adhes" user "F.Adhesive")
		(11 "B.Adhes" user "B.Adhesive")
		(13 "F.Paste" user "Package Geometry/Pastemask Top")
		(15 "B.Paste" user "Package Geometry/Pastemask Bottom")
		(5 "F.SilkS" user "Ref Des/Silkscreen Top")
		(7 "B.SilkS" user "Ref Des/Silkscreen Bottom")
		(1 "F.Mask" user "Board Geometry/Soldermask Top")
		(3 "B.Mask" user "Board Geometry/Soldermask Bottom")
		(17 "Dwgs.User" user "User.Drawings")
		(19 "Cmts.User" user "User.Comments")
		(21 "Eco1.User" user "User.Eco1")
		(23 "Eco2.User" user "User.Eco2")
		(25 "Edge.Cuts" user "Board Geometry/Outline")
		(27 "Margin" user)
		(31 "F.CrtYd" user "Package Geometry/Place Bound Top")
		(29 "B.CrtYd" user "Package Geometry/Place Bound Bottom")
		(35 "F.Fab" user "Ref Des/Assembly Top")
		(33 "B.Fab" user "Ref Des/Assembly Bottom")
	)
	(footprint ""
		(layer "F.Cu")
		(at 62.99708 -258.091686)
		(property "Reference" "J18"
			(at -1.547622 -81.836514 0)
			(unlocked yes)
			(layer "F.SilkS")
			(effects
				(font
					(size 0.7874 0.5842)
					(thickness 0.1524)
				)
				(justify left)
			)
		)
		(property "Value" ""
			(at 0 0 0)
			(layer "F.Fab")
			(effects
				(font
					(size 1.27 1.27)
				)
			)
		)
		(duplicate_pad_numbers_are_jumpers no)
		(pad "1" smd rect
			(at -2.050034 -63.324994 270)
			(size 0.519938 1.4986)
			(layers "F.Cu" "F.Mask" "F.Paste")
			(net "P12V_S3_AUX_CPU1_NVDIMM")
		)
		(pad "2" smd rect
			(at -2.050034 -62.47511 270)
			(size 0.519938 1.4986)
			(layers "F.Cu" "F.Mask" "F.Paste")
			(net "TP_CHA_CPU1_DIMM2_FRU_0")
		)
		(pad "3" smd rect
			(at -2.050034 -61.624972 270)
			(size 0.519938 1.4986)
			(layers "F.Cu" "F.Mask" "F.Paste")
			(net "P3V3_AUX")
		)
		(pad "4" smd rect
			(at -2.050034 -60.775088 270)
			(size 0.519938 1.4986)
			(layers "F.Cu" "F.Mask" "F.Paste")
			(net "I3C_SPD_DDRABCD_CPU1_LVC1_SCL_1")
		)
		(pad "5" smd rect
			(at -2.050034 -59.92495 270)
			(size 0.519938 1.4986)
			(layers "F.Cu" "F.Mask" "F.Paste")
			(net "I3C_SPD_DDRABCD_CPU1_LVC1_SDA")
		)
		(pad "6" smd rect
			(at -2.050034 -59.075066 270)
			(size 0.519938 1.4986)
			(layers "F.Cu" "F.Mask" "F.Paste")
			(net "GND")
		)
		(pad "7" smd rect
			(at -2.050034 -58.224928 270)
			(size 0.519938 1.4986)
			(layers "F.Cu" "F.Mask" "F.Paste")
			(net "M_A_CPU1_SA_DQ<0>")
		)
		(pad "8" smd rect
			(at -2.050034 -57.375044 270)
			(size 0.519938 1.4986)
			(layers "F.Cu" "F.Mask" "F.Paste")
			(net "GND")
		)
		(pad "9" smd rect
			(at -2.050034 -56.524906 270)
			(size 0.519938 1.4986)
			(layers "F.Cu" "F.Mask" "F.Paste")
			(net "M_A_CPU1_SA_DQ<1>")
		)
		(pad "10" smd rect
			(at -2.050034 -55.675022 270)
			(size 0.519938 1.4986)
			(layers "F.Cu" "F.Mask" "F.Paste")
			(net "GND")
		)
		(pad "11" smd rect
			(at -2.050034 -54.824884 270)
			(size 0.519938 1.4986)
			(layers "F.Cu" "F.Mask" "F.Paste")
			(net "M_A_CPU1_SA_DQS_DP<0>")
		)
		(pad "12" smd rect
			(at -2.050034 -53.975 270)
			(size 0.519938 1.4986)
			(layers "F.Cu" "F.Mask" "F.Paste")
			(net "M_A_CPU1_SA_DQS_DN<0>")
		)
		(pad "13" smd rect
			(at -2.050034 -53.125116 270)
			(size 0.519938 1.4986)
			(layers "F.Cu" "F.Mask" "F.Paste")
			(net "GND")
		)
		(pad "14" smd rect
			(at -2.050034 -52.274978 270)
			(size 0.519938 1.4986)
			(layers "F.Cu" "F.Mask" "F.Paste")
			(net "M_A_CPU1_SA_DQ<4>")
		)
		(pad "15" smd rect
			(at -2.050034 -51.425094 270)
			(size 0.519938 1.4986)
			(layers "F.Cu" "F.Mask" "F.Paste")
			(net "GND")
		)
		(pad "16" smd rect
			(at -2.050034 -50.574956 270)
			(size 0.519938 1.4986)
			(layers "F.Cu" "F.Mask" "F.Paste")
			(net "M_A_CPU1_SA_DQ<5>")
		)
		(pad "17" smd rect
			(at -2.050034 -49.725072 270)
			(size 0.519938 1.4986)
			(layers "F.Cu" "F.Mask" "F.Paste")
			(net "GND")
		)
		(pad "18" smd rect
			(at -2.050034 -48.874934 270)
			(size 0.519938 1.4986)
			(layers "F.Cu" "F.Mask" "F.Paste")
			(net "M_A_CPU1_SA_DQ<8>")
		)
		(pad "19" smd rect
			(at -2.050034 -48.02505 270)
			(size 0.519938 1.4986)
			(layers "F.Cu" "F.Mask" "F.Paste")
			(net "GND")
		)
		(pad "20" smd rect
			(at -2.050034 -47.174912 270)
			(size 0.519938 1.4986)
			(layers "F.Cu" "F.Mask" "F.Paste")
			(net "M_A_CPU1_SA_DQ<9>")
		)
		(pad "21" smd rect
			(at -2.050034 -46.325028 270)
			(size 0.519938 1.4986)
			(layers "F.Cu" "F.Mask" "F.Paste")
			(net "GND")
		)
		(pad "22" smd rect
			(at -2.050034 -45.47489 270)
			(size 0.519938 1.4986)
			(layers "F.Cu" "F.Mask" "F.Paste")
			(net "M_A_CPU1_SA_DQS_DP<1>")
		)
		(pad "23" smd rect
			(at -2.050034 -44.625006 270)
			(size 0.519938 1.4986)
			(layers "F.Cu" "F.Mask" "F.Paste")
			(net "M_A_CPU1_SA_DQS_DN<1>")
		)
		(pad "24" smd rect
			(at -2.050034 -43.775122 270)
			(size 0.519938 1.4986)
			(layers "F.Cu" "F.Mask" "F.Paste")
			(net "GND")
		)
		(pad "25" smd rect
			(at -2.050034 -42.924984 270)
			(size 0.519938 1.4986)
			(layers "F.Cu" "F.Mask" "F.Paste")
			(net "M_A_CPU1_SA_DQ<12>")
		)
		(pad "26" smd rect
			(at -2.050034 -42.0751 270)
			(size 0.519938 1.4986)
			(layers "F.Cu" "F.Mask" "F.Paste")
			(net "GND")
		)
		(pad "27" smd rect
			(at -2.050034 -41.224962 270)
			(size 0.519938 1.4986)
			(layers "F.Cu" "F.Mask" "F.Paste")
			(net "M_A_CPU1_SA_DQ<13>")
		)
		(pad "28" smd rect
			(at -2.050034 -40.375078 270)
			(size 0.519938 1.4986)
			(layers "F.Cu" "F.Mask" "F.Paste")
			(net "GND")
		)
		(pad "29" smd rect
			(at -2.050034 -39.52494 270)
			(size 0.519938 1.4986)
			(layers "F.Cu" "F.Mask" "F.Paste")
			(net "M_A_CPU1_SA_DQ<16>")
		)
		(pad "30" smd rect
			(at -2.050034 -38.675056 270)
			(size 0.519938 1.4986)
			(layers "F.Cu" "F.Mask" "F.Paste")
			(net "GND")
		)
		(pad "31" smd rect
			(at -2.050034 -37.824918 270)
			(size 0.519938 1.4986)
			(layers "F.Cu" "F.Mask" "F.Paste")
			(net "M_A_CPU1_SA_DQ<17>")
		)
		(pad "32" smd rect
			(at -2.050034 -36.975034 270)
			(size 0.519938 1.4986)
			(layers "F.Cu" "F.Mask" "F.Paste")
			(net "GND")
		)
		(pad "33" smd rect
			(at -2.050034 -36.124896 270)
			(size 0.519938 1.4986)
			(layers "F.Cu" "F.Mask" "F.Paste")
			(net "M_A_CPU1_SA_DQS_DP<2>")
		)
		(pad "34" smd rect
			(at -2.050034 -35.275012 270)
			(size 0.519938 1.4986)
			(layers "F.Cu" "F.Mask" "F.Paste")
			(net "M_A_CPU1_SA_DQS_DN<2>")
		)
		(pad "35" smd rect
			(at -2.050034 -34.425128 270)
			(size 0.519938 1.4986)
			(layers "F.Cu" "F.Mask" "F.Paste")
			(net "GND")
		)
		(pad "36" smd rect
			(at -2.050034 -33.57499 270)
			(size 0.519938 1.4986)
			(layers "F.Cu" "F.Mask" "F.Paste")
			(net "M_A_CPU1_SA_DQ<20>")
		)
		(pad "37" smd rect
			(at -2.050034 -32.725106 270)
			(size 0.519938 1.4986)
			(layers "F.Cu" "F.Mask" "F.Paste")
			(net "GND")
		)
		(pad "38" smd rect
			(at -2.050034 -31.874968 270)
			(size 0.519938 1.4986)
			(layers "F.Cu" "F.Mask" "F.Paste")
			(net "M_A_CPU1_SA_DQ<21>")
		)
		(pad "39" smd rect
			(at -2.050034 -31.025084 270)
			(size 0.519938 1.4986)
			(layers "F.Cu" "F.Mask" "F.Paste")
			(net "GND")
		)
		(pad "40" smd rect
			(at -2.050034 -30.174946 270)
			(size 0.519938 1.4986)
			(layers "F.Cu" "F.Mask" "F.Paste")
			(net "M_A_CPU1_SA_DQ<24>")
		)
		(pad "41" smd rect
			(at -2.050034 -29.325062 270)
			(size 0.519938 1.4986)
			(layers "F.Cu" "F.Mask" "F.Paste")
			(net "GND")
		)
		(pad "42" smd rect
			(at -2.050034 -28.474924 270)
			(size 0.519938 1.4986)
			(layers "F.Cu" "F.Mask" "F.Paste")
			(net "M_A_CPU1_SA_DQ<25>")
		)
		(pad "43" smd rect
			(at -2.050034 -27.62504 270)
			(size 0.519938 1.4986)
			(layers "F.Cu" "F.Mask" "F.Paste")
			(net "GND")
		)
		(pad "44" smd rect
			(at -2.050034 -26.774902 270)
			(size 0.519938 1.4986)
			(layers "F.Cu" "F.Mask" "F.Paste")
			(net "M_A_CPU1_SA_DQS_DP<3>")
		)
		(pad "45" smd rect
			(at -2.050034 -25.925018 270)
			(size 0.519938 1.4986)
			(layers "F.Cu" "F.Mask" "F.Paste")
			(net "M_A_CPU1_SA_DQS_DN<3>")
		)
		(pad "46" smd rect
			(at -2.050034 -25.07488 270)
			(size 0.519938 1.4986)
			(layers "F.Cu" "F.Mask" "F.Paste")
			(net "GND")
		)
		(pad "47" smd rect
			(at -2.050034 -24.224996 270)
			(size 0.519938 1.4986)
			(layers "F.Cu" "F.Mask" "F.Paste")
			(net "M_A_CPU1_SA_DQ<28>")
		)
		(pad "48" smd rect
			(at -2.050034 -23.375112 270)
			(size 0.519938 1.4986)
			(layers "F.Cu" "F.Mask" "F.Paste")
			(net "GND")
		)
		(pad "49" smd rect
			(at -2.050034 -22.524974 270)
			(size 0.519938 1.4986)
			(layers "F.Cu" "F.Mask" "F.Paste")
			(net "M_A_CPU1_SA_DQ<29>")
		)
		(pad "50" smd rect
			(at -2.050034 -21.67509 270)
			(size 0.519938 1.4986)
			(layers "F.Cu" "F.Mask" "F.Paste")
			(net "GND")
		)
		(pad "51" smd rect
			(at -2.050034 -20.824952 270)
			(size 0.519938 1.4986)
			(layers "F.Cu" "F.Mask" "F.Paste")
			(net "M_A_CPU1_SA_CB<0>")
		)
		(pad "52" smd rect
			(at -2.050034 -19.975068 270)
			(size 0.519938 1.4986)
			(layers "F.Cu" "F.Mask" "F.Paste")
			(net "GND")
		)
		(pad "53" smd rect
			(at -2.050034 -19.12493 270)
			(size 0.519938 1.4986)
			(layers "F.Cu" "F.Mask" "F.Paste")
			(net "M_A_CPU1_SA_CB<1>")
		)
		(pad "54" smd rect
			(at -2.050034 -18.275046 270)
			(size 0.519938 1.4986)
			(layers "F.Cu" "F.Mask" "F.Paste")
			(net "GND")
		)
		(pad "55" smd rect
			(at -2.050034 -17.424908 270)
			(size 0.519938 1.4986)
			(layers "F.Cu" "F.Mask" "F.Paste")
			(net "M_A_CPU1_SA_DQS_DP<4>")
		)
		(pad "56" smd rect
			(at -2.050034 -16.575024 270)
			(size 0.519938 1.4986)
			(layers "F.Cu" "F.Mask" "F.Paste")
			(net "M_A_CPU1_SA_DQS_DN<4>")
		)
		(pad "57" smd rect
			(at -2.050034 -15.724886 270)
			(size 0.519938 1.4986)
			(layers "F.Cu" "F.Mask" "F.Paste")
			(net "GND")
		)
		(pad "58" smd rect
			(at -2.050034 -14.875002 270)
			(size 0.519938 1.4986)
			(layers "F.Cu" "F.Mask" "F.Paste")
			(net "M_A_CPU1_SA_CB<4>")
		)
		(pad "59" smd rect
			(at -2.050034 -14.025118 270)
			(size 0.519938 1.4986)
			(layers "F.Cu" "F.Mask" "F.Paste")
			(net "GND")
		)
		(pad "60" smd rect
			(at -2.050034 -13.17498 270)
			(size 0.519938 1.4986)
			(layers "F.Cu" "F.Mask" "F.Paste")
			(net "M_A_CPU1_SA_CB<5>")
		)
		(pad "61" smd rect
			(at -2.050034 -12.325096 270)
			(size 0.519938 1.4986)
			(layers "F.Cu" "F.Mask" "F.Paste")
			(net "GND")
		)
		(pad "62" smd rect
			(at -2.050034 -11.474958 270)
			(size 0.519938 1.4986)
			(layers "F.Cu" "F.Mask" "F.Paste")
			(net "M_A_CPU1_ALERT_N")
		)
		(pad "63" smd rect
			(at -2.050034 -10.625074 270)
			(size 0.519938 1.4986)
			(layers "F.Cu" "F.Mask" "F.Paste")
			(net "GND")
		)
		(pad "64" smd rect
			(at -2.050034 -9.774936 270)
			(size 0.519938 1.4986)
			(layers "F.Cu" "F.Mask" "F.Paste")
			(net "M_A_CPU1_SA_CS_N<2>")
		)
		(pad "65" smd rect
			(at -2.050034 -8.925052 270)
			(size 0.519938 1.4986)
			(layers "F.Cu" "F.Mask" "F.Paste")
			(net "GND")
		)
		(pad "66" smd rect
			(at -2.050034 -8.074914 270)
			(size 0.519938 1.4986)
			(layers "F.Cu" "F.Mask" "F.Paste")
			(net "M_A_CPU1_SA_CA<0>")
		)
		(pad "67" smd rect
			(at -2.050034 -7.22503 270)
			(size 0.519938 1.4986)
			(layers "F.Cu" "F.Mask" "F.Paste")
			(net "GND")
		)
		(pad "68" smd rect
			(at -2.050034 -6.374892 270)
			(size 0.519938 1.4986)
			(layers "F.Cu" "F.Mask" "F.Paste")
			(net "M_A_CPU1_SA_CA<2>")
		)
		(pad "69" smd rect
			(at -2.050034 -5.525008 270)
			(size 0.519938 1.4986)
			(layers "F.Cu" "F.Mask" "F.Paste")
			(net "GND")
		)
		(pad "70" smd rect
			(at -2.050034 -4.675124 270)
			(size 0.519938 1.4986)
			(layers "F.Cu" "F.Mask" "F.Paste")
			(net "M_A_CPU1_SA_CA<4>")
		)
		(pad "71" smd rect
			(at -2.050034 -3.824986 270)
			(size 0.519938 1.4986)
			(layers "F.Cu" "F.Mask" "F.Paste")
			(net "GND")
		)
		(pad "72" smd rect
			(at -2.050034 -2.975102 270)
			(size 0.519938 1.4986)
			(layers "F.Cu" "F.Mask" "F.Paste")
			(net "M_A_CPU1_SA_CA<6>")
		)
		(pad "73" smd rect
			(at -2.050034 -2.124964 270)
			(size 0.519938 1.4986)
			(layers "F.Cu" "F.Mask" "F.Paste")
			(net "GND")
		)
		(pad "74" smd rect
			(at -2.050034 -1.27508 270)
			(size 0.519938 1.4986)
			(layers "F.Cu" "F.Mask" "F.Paste")
			(net "M_A_CPU1_SA_PAR")
		)
		(pad "75" smd rect
			(at -2.050034 -0.424942 270)
			(size 0.519938 1.4986)
			(layers "F.Cu" "F.Mask" "F.Paste")
			(net "GND")
		)
		(pad "76" smd rect
			(at -2.050034 5.525008 270)
			(size 0.519938 1.4986)
			(layers "F.Cu" "F.Mask" "F.Paste")
			(net "M_A_CPU1_SB_CA<0>")
		)
		(pad "77" smd rect
			(at -2.050034 6.374892 270)
			(size 0.519938 1.4986)
			(layers "F.Cu" "F.Mask" "F.Paste")
			(net "GND")
		)
		(pad "78" smd rect
			(at -2.050034 7.22503 270)
			(size 0.519938 1.4986)
			(layers "F.Cu" "F.Mask" "F.Paste")
			(net "M_A_CPU1_SB_CA<2>")
		)
		(pad "79" smd rect
			(at -2.050034 8.074914 270)
			(size 0.519938 1.4986)
			(layers "F.Cu" "F.Mask" "F.Paste")
			(net "GND")
		)
		(pad "80" smd rect
			(at -2.050034 8.925052 270)
			(size 0.519938 1.4986)
			(layers "F.Cu" "F.Mask" "F.Paste")
			(net "M_A_CPU1_SB_CA<4>")
		)
		(pad "81" smd rect
			(at -2.050034 9.774936 270)
			(size 0.519938 1.4986)
			(layers "F.Cu" "F.Mask" "F.Paste")
			(net "GND")
		)
		(pad "82" smd rect
			(at -2.050034 10.625074 270)
			(size 0.519938 1.4986)
			(layers "F.Cu" "F.Mask" "F.Paste")
			(net "M_A_CPU1_SB_CA<6>")
		)
		(pad "83" smd rect
			(at -2.050034 11.474958 270)
			(size 0.519938 1.4986)
			(layers "F.Cu" "F.Mask" "F.Paste")
			(net "GND")
		)
		(pad "84" smd rect
			(at -2.050034 12.325096 270)
			(size 0.519938 1.4986)
			(layers "F.Cu" "F.Mask" "F.Paste")
			(net "M_A_CPU1_SB_CS_N<2>")
		)
		(pad "85" smd rect
			(at -2.050034 13.17498 270)
			(size 0.519938 1.4986)
			(layers "F.Cu" "F.Mask" "F.Paste")
			(net "GND")
		)
		(pad "86" smd rect
			(at -2.050034 14.025118 270)
			(size 0.519938 1.4986)
			(layers "F.Cu" "F.Mask" "F.Paste")
			(net "M_A_CPU1_SA_RSP<1>")
		)
		(pad "87" smd rect
			(at -2.050034 14.875002 270)
			(size 0.519938 1.4986)
			(layers "F.Cu" "F.Mask" "F.Paste")
			(net "M_A_CPU1_SB_RSP<1>")
		)
		(pad "88" smd rect
			(at -2.050034 15.724886 270)
			(size 0.519938 1.4986)
			(layers "F.Cu" "F.Mask" "F.Paste")
			(net "GND")
		)
		(pad "89" smd rect
			(at -2.050034 16.575024 270)
			(size 0.519938 1.4986)
			(layers "F.Cu" "F.Mask" "F.Paste")
			(net "M_A_CPU1_SB_CB<4>")
		)
		(pad "90" smd rect
			(at -2.050034 17.424908 270)
			(size 0.519938 1.4986)
			(layers "F.Cu" "F.Mask" "F.Paste")
			(net "GND")
		)
		(pad "91" smd rect
			(at -2.050034 18.275046 270)
			(size 0.519938 1.4986)
			(layers "F.Cu" "F.Mask" "F.Paste")
			(net "M_A_CPU1_SB_CB<5>")
		)
		(pad "92" smd rect
			(at -2.050034 19.12493 270)
			(size 0.519938 1.4986)
			(layers "F.Cu" "F.Mask" "F.Paste")
			(net "GND")
		)
		(pad "93" smd rect
			(at -2.050034 19.975068 270)
			(size 0.519938 1.4986)
			(layers "F.Cu" "F.Mask" "F.Paste")
			(net "M_A_CPU1_SB_DQS_DP<9>")
		)
		(pad "94" smd rect
			(at -2.050034 20.824952 270)
			(size 0.519938 1.4986)
			(layers "F.Cu" "F.Mask" "F.Paste")
			(net "M_A_CPU1_SB_DQS_DN<9>")
		)
		(pad "95" smd rect
			(at -2.050034 21.67509 270)
			(size 0.519938 1.4986)
			(layers "F.Cu" "F.Mask" "F.Paste")
			(net "GND")
		)
		(pad "96" smd rect
			(at -2.050034 22.524974 270)
			(size 0.519938 1.4986)
			(layers "F.Cu" "F.Mask" "F.Paste")
			(net "M_A_CPU1_SB_CB<0>")
		)
		(pad "97" smd rect
			(at -2.050034 23.375112 270)
			(size 0.519938 1.4986)
			(layers "F.Cu" "F.Mask" "F.Paste")
			(net "GND")
		)
		(pad "98" smd rect
			(at -2.050034 24.224996 270)
			(size 0.519938 1.4986)
			(layers "F.Cu" "F.Mask" "F.Paste")
			(net "M_A_CPU1_SB_CB<1>")
		)
		(pad "99" smd rect
			(at -2.050034 25.07488 270)
			(size 0.519938 1.4986)
			(layers "F.Cu" "F.Mask" "F.Paste")
			(net "GND")
		)
		(pad "100" smd rect
			(at -2.050034 25.925018 270)
			(size 0.519938 1.4986)
			(layers "F.Cu" "F.Mask" "F.Paste")
			(net "M_A_CPU1_SB_DQ<0>")
		)
		(pad "101" smd rect
			(at -2.050034 26.774902 270)
			(size 0.519938 1.4986)
			(layers "F.Cu" "F.Mask" "F.Paste")
			(net "GND")
		)
		(pad "102" smd rect
			(at -2.050034 27.62504 270)
			(size 0.519938 1.4986)
			(layers "F.Cu" "F.Mask" "F.Paste")
			(net "M_A_CPU1_SB_DQ<1>")
		)
		(pad "103" smd rect
			(at -2.050034 28.474924 270)
			(size 0.519938 1.4986)
			(layers "F.Cu" "F.Mask" "F.Paste")
			(net "GND")
		)
		(pad "104" smd rect
			(at -2.050034 29.325062 270)
			(size 0.519938 1.4986)
			(layers "F.Cu" "F.Mask" "F.Paste")
			(net "M_A_CPU1_SB_DQS_DP<0>")
		)
		(pad "105" smd rect
			(at -2.050034 30.174946 270)
			(size 0.519938 1.4986)
			(layers "F.Cu" "F.Mask" "F.Paste")
			(net "M_A_CPU1_SB_DQS_DN<0>")
		)
		(pad "106" smd rect
			(at -2.050034 31.025084 270)
			(size 0.519938 1.4986)
			(layers "F.Cu" "F.Mask" "F.Paste")
			(net "GND")
		)
		(pad "107" smd rect
			(at -2.050034 31.874968 270)
			(size 0.519938 1.4986)
			(layers "F.Cu" "F.Mask" "F.Paste")
			(net "M_A_CPU1_SB_DQ<4>")
		)
		(pad "108" smd rect
			(at -2.050034 32.725106 270)
			(size 0.519938 1.4986)
			(layers "F.Cu" "F.Mask" "F.Paste")
			(net "GND")
		)
		(pad "109" smd rect
			(at -2.050034 33.57499 270)
			(size 0.519938 1.4986)
			(layers "F.Cu" "F.Mask" "F.Paste")
			(net "M_A_CPU1_SB_DQ<5>")
		)
		(pad "110" smd rect
			(at -2.050034 34.425128 270)
			(size 0.519938 1.4986)
			(layers "F.Cu" "F.Mask" "F.Paste")
			(net "GND")
		)
		(pad "111" smd rect
			(at -2.050034 35.275012 270)
			(size 0.519938 1.4986)
			(layers "F.Cu" "F.Mask" "F.Paste")
			(net "M_A_CPU1_SB_DQ<8>")
		)
		(pad "112" smd rect
			(at -2.050034 36.124896 270)
			(size 0.519938 1.4986)
			(layers "F.Cu" "F.Mask" "F.Paste")
			(net "GND")
		)
	)
)
